# SCM (Grand Teton) — schematic netlist excerpt (pin names and nets, part order shuffled) for the footprints in the layout excerpt that follows; sources: Cadence DE-HDL packaged netlist, KiCad conversion of 12092022_DA0F0TMDCD0_F0T_Management_Board_D_brd_V3_OCP.brd

L14  Q_INDUCTOR  BLM18PG121SN1D/2000MA IND  pkg SMLF  page 17 : \1\ = P1V8_AUX ; \2\ = P1V8_STBY_RC_VCC18A
C36  Q_CAP  0.1UF 25V 10% X7R  pkg 0402  page 15 : A = P3V3_P1V8_SD1VDD ; B = GND

(kicad_pcb
	(version 20260206)
	(generator "pcbnew")
	(generator_version "10.0")
	(general
		(thickness 1.6)
		(legacy_teardrops no)
	)
	(paper "A4")
	(title_block
		(title "12092022_DA0F0TMDCD0_F0T_Management_Board_D_brd_V3_OCP.brd")
		(comment 1 "Grand Teton / footprints 1201-1202 of 1440")
	)
	(layers
		(0 "F.Cu" signal "TOP")
		(4 "In1.Cu" signal "GND")
		(6 "In2.Cu" signal "IN1")
		(8 "In3.Cu" signal "GND1")
		(10 "In4.Cu" signal "IN2")
		(12 "In5.Cu" signal "VCC")
		(14 "In6.Cu" signal "VCC1")
		(16 "In7.Cu" signal "IN3")
		(18 "In8.Cu" signal "GND2")
		(20 "In9.Cu" signal "IN4")
		(22 "In10.Cu" signal "GND3")
		(2 "B.Cu" signal "BOTTOM")
		(9 "F.Adhes" user "F.Adhesive")
		(11 "B.Adhes" user "B.Adhesive")
		(13 "F.Paste" user "Package Geometry/Pastemask Top")
		(15 "B.Paste" user "Package Geometry/Pastemask Bottom")
		(5 "F.SilkS" user "Ref Des/Silkscreen Top")
		(7 "B.SilkS" user "Ref Des/Silkscreen Bottom")
		(1 "F.Mask" user "Board Geometry/Soldermask Top")
		(3 "B.Mask" user "Board Geometry/Soldermask Bottom")
		(17 "Dwgs.User" user "User.Drawings")
		(19 "Cmts.User" user "User.Comments")
		(21 "Eco1.User" user "User.Eco1")
		(23 "Eco2.User" user "User.Eco2")
		(25 "Edge.Cuts" user "Board Geometry/Outline")
		(27 "Margin" user)
		(31 "F.CrtYd" user "Package Geometry/Place Bound Top")
		(29 "B.CrtYd" user "Package Geometry/Place Bound Bottom")
		(35 "F.Fab" user "Ref Des/Assembly Top")
		(33 "B.Fab" user "Ref Des/Assembly Bottom")
	)
	(footprint ""
		(layer "B.Cu")
		(at 69.102478 -65.406016 90)
		(property "Reference" "L14"
			(at 0 0 90)
			(layer "B.SilkS")
			(hide yes)
			(effects
				(font
					(size 1.27 1.27)
				)
				(justify mirror)
			)
		)
		(property "Value" ""
			(at 0 0 90)
			(layer "B.Fab")
			(effects
				(font
					(size 1.27 1.27)
				)
				(justify mirror)
			)
		)
		(duplicate_pad_numbers_are_jumpers no)
		(fp_line
			(start 1.27 -0.5842)
			(end -1.27 -0.5842)
			(stroke
				(width 0.1524)
				(type default)
			)
			(layer "B.SilkS")
		)
		(fp_line
			(start 1.27 -0.5588)
			(end 1.27 -0.5842)
			(stroke
				(width 0.1524)
				(type default)
			)
			(layer "B.SilkS")
		)
		(fp_line
			(start 1.27 0.5842)
			(end 1.27 -0.5842)
			(stroke
				(width 0.1524)
				(type default)
			)
			(layer "B.SilkS")
		)
		(fp_line
			(start 0.127 0.5842)
			(end 0.127 -0.5842)
			(stroke
				(width 0.1524)
				(type default)
			)
			(layer "B.SilkS")
		)
		(fp_line
			(start -0.127 0.5842)
			(end -0.127 -0.5842)
			(stroke
				(width 0.1524)
				(type default)
			)
			(layer "B.SilkS")
		)
		(fp_line
			(start -1.27 0.5842)
			(end -1.27 -0.5842)
			(stroke
				(width 0.1524)
				(type default)
			)
			(layer "B.SilkS")
		)
		(fp_line
			(start -1.27 0.5842)
			(end 1.27 0.5842)
			(stroke
				(width 0.1524)
				(type default)
			)
			(layer "B.SilkS")
		)
		(fp_line
			(start 0.9144 -0.508)
			(end -0.9144 -0.508)
			(stroke
				(width 0.1)
				(type default)
			)
			(layer "B.Fab")
		)
		(fp_line
			(start -0.9144 -0.508)
			(end -0.9144 -0.406654)
			(stroke
				(width 0.1)
				(type default)
			)
			(layer "B.Fab")
		)
		(fp_line
			(start 1.194308 -0.406654)
			(end 0.9144 -0.406654)
			(stroke
				(width 0.1)
				(type default)
			)
			(layer "B.Fab")
		)
		(fp_line
			(start 0.9144 -0.406654)
			(end 0.9144 -0.508)
			(stroke
				(width 0.1)
				(type default)
			)
			(layer "B.Fab")
		)
		(fp_line
			(start -0.9144 -0.406654)
			(end -1.1938 -0.406654)
			(stroke
				(width 0.1)
				(type default)
			)
			(layer "B.Fab")
		)
		(fp_line
			(start -1.1938 -0.406654)
			(end -1.1938 0.4064)
			(stroke
				(width 0.1)
				(type default)
			)
			(layer "B.Fab")
		)
		(fp_line
			(start -0.9144 0.4064)
			(end -0.9144 0.508)
			(stroke
				(width 0.1)
				(type default)
			)
			(layer "B.Fab")
		)
		(fp_line
			(start -1.1938 0.4064)
			(end -0.9144 0.4064)
			(stroke
				(width 0.1)
				(type default)
			)
			(layer "B.Fab")
		)
		(fp_line
			(start 1.194308 0.406654)
			(end 1.194308 -0.406654)
			(stroke
				(width 0.1)
				(type default)
			)
			(layer "B.Fab")
		)
		(fp_line
			(start 0.9144 0.406654)
			(end 1.194308 0.406654)
			(stroke
				(width 0.1)
				(type default)
			)
			(layer "B.Fab")
		)
		(fp_line
			(start 0.9144 0.508)
			(end 0.9144 0.406654)
			(stroke
				(width 0.1)
				(type default)
			)
			(layer "B.Fab")
		)
		(fp_line
			(start -0.9144 0.508)
			(end 0.9144 0.508)
			(stroke
				(width 0.1)
				(type default)
			)
			(layer "B.Fab")
		)
		(pad "1" smd rect
			(at 0.7366 0)
			(size 0.7112 0.8128)
			(layers "B.Cu" "B.Mask" "B.Paste")
			(net "P1V8_AUX")
		)
		(pad "2" smd rect
			(at -0.7366 0)
			(size 0.7112 0.8128)
			(layers "B.Cu" "B.Mask" "B.Paste")
			(net "P1V8_STBY_RC_VCC18A")
		)
	)
	(footprint ""
		(layer "B.Cu")
		(at 49.1617 -43.986704 90)
		(property "Reference" "C36"
			(at 0 0 90)
			(layer "B.SilkS")
			(hide yes)
			(effects
				(font
					(size 1.27 1.27)
				)
				(justify mirror)
			)
		)
		(property "Value" ""
			(at 0 0 90)
			(layer "B.Fab")
			(effects
				(font
					(size 1.27 1.27)
				)
				(justify mirror)
			)
		)
		(duplicate_pad_numbers_are_jumpers no)
		(fp_line
			(start 0.7874 -0.4064)
			(end -0.7874 -0.4064)
			(stroke
				(width 0.1524)
				(type default)
			)
			(layer "B.SilkS")
		)
		(fp_line
			(start -0.7874 -0.4064)
			(end -0.7874 0.4064)
			(stroke
				(width 0.1524)
				(type default)
			)
			(layer "B.SilkS")
		)
		(fp_line
			(start 0.7874 0.4064)
			(end 0.7874 -0.4064)
			(stroke
				(width 0.1524)
				(type default)
			)
			(layer "B.SilkS")
		)
		(fp_line
			(start -0.7874 0.4064)
			(end 0.7874 0.4064)
			(stroke
				(width 0.1524)
				(type default)
			)
			(layer "B.SilkS")
		)
		(fp_line
			(start 0.67945 -0.305054)
			(end 0.12065 -0.305054)
			(stroke
				(width 0.1)
				(type default)
			)
			(layer "B.Fab")
		)
		(fp_line
			(start 0.12065 -0.305054)
			(end 0.12065 -0.2794)
			(stroke
				(width 0.1)
				(type default)
			)
			(layer "B.Fab")
		)
		(fp_line
			(start -0.12065 -0.3048)
			(end -0.67945 -0.3048)
			(stroke
				(width 0.1)
				(type default)
			)
			(layer "B.Fab")
		)
		(fp_line
			(start -0.67945 -0.3048)
			(end -0.67945 0.3048)
			(stroke
				(width 0.1)
				(type default)
			)
			(layer "B.Fab")
		)
		(fp_line
			(start 0.12065 -0.2794)
			(end -0.12065 -0.2794)
			(stroke
				(width 0.1)
				(type default)
			)
			(layer "B.Fab")
		)
		(fp_line
			(start -0.12065 -0.2794)
			(end -0.12065 -0.3048)
			(stroke
				(width 0.1)
				(type default)
			)
			(layer "B.Fab")
		)
		(fp_line
			(start 0.12065 0.2794)
			(end 0.12065 0.3048)
			(stroke
				(width 0.1)
				(type default)
			)
			(layer "B.Fab")
		)
		(fp_line
			(start -0.120396 0.2794)
			(end 0.12065 0.2794)
			(stroke
				(width 0.1)
				(type default)
			)
			(layer "B.Fab")
		)
		(fp_line
			(start 0.67945 0.3048)
			(end 0.67945 -0.305054)
			(stroke
				(width 0.1)
				(type default)
			)
			(layer "B.Fab")
		)
		(fp_line
			(start 0.12065 0.3048)
			(end 0.67945 0.3048)
			(stroke
				(width 0.1)
				(type default)
			)
			(layer "B.Fab")
		)
		(fp_line
			(start -0.120396 0.3048)
			(end -0.120396 0.2794)
			(stroke
				(width 0.1)
				(type default)
			)
			(layer "B.Fab")
		)
		(fp_line
			(start -0.67945 0.3048)
			(end -0.120396 0.3048)
			(stroke
				(width 0.1)
				(type default)
			)
			(layer "B.Fab")
		)
		(pad "1" smd circle
			(at 0.40005 0 270)
			(size 0 0)
			(layers "B.Cu" "B.Mask" "B.Paste")
			(net "P3V3_P1V8_SD1VDD")
		)
		(pad "2" smd circle
			(at -0.40005 0 270)
			(size 0 0)
			(layers "B.Cu" "B.Mask" "B.Paste")
			(net "GND")
		)
	)
)
